(kicad_pcb
	(version 20240108)
	(generator "pcbnew")
	(generator_version "8.0")
	(general
		(thickness 1.62)
		(legacy_teardrops no)
	)
	(paper "A4")
	(title_block
		(title "Jetson Orin Baseboard")
		(date "2025-03-12")
		(rev "1.3.4")
		(company "Antmicro Ltd")
		(comment 1 "www.antmicro.com")
		(comment 9 "footprints 305-307 of 677")
	)
	(layers
		(0 "F.Cu" signal)
		(1 "In1.Cu" signal)
		(2 "In2.Cu" signal)
		(3 "In3.Cu" signal)
		(4 "In4.Cu" jumper)
		(5 "In5.Cu" signal)
		(6 "In6.Cu" signal)
		(31 "B.Cu" signal)
		(32 "B.Adhes" user "B.Adhesive")
		(33 "F.Adhes" user "F.Adhesive")
		(34 "B.Paste" user)
		(35 "F.Paste" user)
		(36 "B.SilkS" user "B.Silkscreen")
		(37 "F.SilkS" user "F.Silkscreen")
		(38 "B.Mask" user)
		(39 "F.Mask" user)
		(40 "Dwgs.User" user "User.Drawings")
		(41 "Cmts.User" user "User.Comments")
		(42 "Eco1.User" user "User.Eco1")
		(43 "Eco2.User" user "User.Eco2")
		(44 "Edge.Cuts" user)
		(45 "Margin" user)
		(46 "B.CrtYd" user "B.Courtyard")
		(47 "F.CrtYd" user "F.Courtyard")
		(48 "B.Fab" user)
		(49 "F.Fab" user)
	)
	(footprint "antmicro-footprints:VQFN-20_5x5x1mm_P0.65mm"
		(layer "B.Cu")
		(at 51.2 87.4375 90)
		(property "Reference" "U22"
			(at 2.9125 3.025 0)
			(layer "B.SilkS")
			(effects
				(font
					(size 0.7 0.7)
					(thickness 0.15)
				)
				(justify left bottom mirror)
			)
		)
		(property "Value" "TPS2372-3RGWR"
			(at 0 -3.883 -90)
			(layer "B.Fab")
			(effects
				(font
					(size 0.7 0.7)
					(thickness 0.15)
				)
				(justify left bottom mirror)
			)
		)
		(property "Footprint" "antmicro-footprints:VQFN-20_5x5x1mm_P0.65mm"
			(at 0 0 90)
			(layer "F.Fab")
			(hide yes)
			(effects
				(font
					(size 1.27 1.27)
					(thickness 0.15)
				)
			)
		)
		(property "Datasheet" "https://www.ti.com/lit/ds/symlink/tps2372.pdf?ts=1679042478513&ref_url=https%253A%252F%252Fwww.google.com%252F"
			(at 0 0 90)
			(layer "F.Fab")
			(hide yes)
			(effects
				(font
					(size 1.27 1.27)
					(thickness 0.15)
				)
			)
		)
		(property "Author" "Antmicro"
			(at 138.6375 36.2375 0)
			(layer "B.Fab")
			(hide yes)
			(effects
				(font
					(size 1 1)
					(thickness 0.15)
				)
				(justify mirror)
			)
		)
		(property "License" "Apache-2.0"
			(at 138.6375 36.2375 0)
			(layer "B.Fab")
			(hide yes)
			(effects
				(font
					(size 1 1)
					(thickness 0.15)
				)
				(justify mirror)
			)
		)
		(property "MPN" "TPS2372-3RGWR"
			(at 138.6375 36.2375 0)
			(layer "B.Fab")
			(hide yes)
			(effects
				(font
					(size 1 1)
					(thickness 0.15)
				)
				(justify mirror)
			)
		)
		(property "Manufacturer" "Texas Instruments"
			(at 138.6375 36.2375 0)
			(layer "B.Fab")
			(hide yes)
			(effects
				(font
					(size 1 1)
					(thickness 0.15)
				)
				(justify mirror)
			)
		)
		(sheetname "Ethernet")
		(sheetfile "ethernet.kicad_sch")
		(attr smd)
		(fp_poly
			(pts
				(xy 0.108 -0.088) (xy 1.08 -0.088) (xy 1.08 -1.08) (xy 0.108 -1.08)
			)
			(stroke
				(width 0.01)
				(type solid)
			)
			(fill solid)
			(layer "B.Paste")
		)
		(fp_poly
			(pts
				(xy -1.081 -0.088) (xy -0.11 -0.088) (xy -0.11 -1.08) (xy -1.081 -1.08)
			)
			(stroke
				(width 0.01)
				(type solid)
			)
			(fill solid)
			(layer "B.Paste")
		)
		(fp_poly
			(pts
				(xy 0.108 1.081) (xy 1.08 1.081) (xy 1.08 0.09) (xy 0.108 0.09)
			)
			(stroke
				(width 0.01)
				(type solid)
			)
			(fill solid)
			(layer "B.Paste")
		)
		(fp_poly
			(pts
				(xy -1.081 1.081) (xy -0.11 1.081) (xy -0.11 0.09) (xy -1.081 0.09)
			)
			(stroke
				(width 0.01)
				(type solid)
			)
			(fill solid)
			(layer "B.Paste")
		)
		(fp_line
			(start 1.789 -2.499)
			(end 2.499 -2.499)
			(stroke
				(width 0.15)
				(type solid)
			)
			(layer "B.SilkS")
		)
		(fp_line
			(start -1.79 -2.499)
			(end -2.5 -2.499)
			(stroke
				(width 0.15)
				(type solid)
			)
			(layer "B.SilkS")
		)
		(fp_line
			(start 2.499 -1.789)
			(end 2.499 -2.499)
			(stroke
				(width 0.15)
				(type solid)
			)
			(layer "B.SilkS")
		)
		(fp_line
			(start -2.5 -1.789)
			(end -2.5 -2.499)
			(stroke
				(width 0.15)
				(type solid)
			)
			(layer "B.SilkS")
		)
		(fp_line
			(start 2.499 1.79)
			(end 2.499 2.5)
			(stroke
				(width 0.15)
				(type solid)
			)
			(layer "B.SilkS")
		)
		(fp_line
			(start 1.789 2.5)
			(end 2.499 2.5)
			(stroke
				(width 0.15)
				(type solid)
			)
			(layer "B.SilkS")
		)
		(fp_line
			(start -2.5 2.5)
			(end -1.625 2.5)
			(stroke
				(width 0.15)
				(type solid)
			)
			(layer "B.SilkS")
		)
		(fp_circle
			(center -2.775 1.875)
			(end -2.725 1.825)
			(stroke
				(width 0.15)
				(type solid)
			)
			(fill solid)
			(layer "B.SilkS")
		)
		(fp_rect
			(start -2.95 2.95)
			(end 2.95 -2.95)
			(stroke
				(width 0.05)
				(type solid)
			)
			(fill none)
			(layer "B.CrtYd")
		)
		(fp_line
			(start -2.5 -2.499)
			(end 2.499 -2.499)
			(stroke
				(width 0.15)
				(type solid)
			)
			(layer "B.Fab")
		)
		(fp_line
			(start -2.5 1.65)
			(end -2.5 -2.499)
			(stroke
				(width 0.15)
				(type solid)
			)
			(layer "B.Fab")
		)
		(fp_line
			(start 2.499 2.5)
			(end 2.499 -2.499)
			(stroke
				(width 0.15)
				(type solid)
			)
			(layer "B.Fab")
		)
		(fp_line
			(start -1.65 2.5)
			(end -2.5 1.65)
			(stroke
				(width 0.15)
				(type solid)
			)
			(layer "B.Fab")
		)
		(fp_line
			(start -1.65 2.5)
			(end 2.499 2.5)
			(stroke
				(width 0.15)
				(type solid)
			)
			(layer "B.Fab")
		)
		(fp_text user "Author: Antmicro"
			(at -2.5 -6.884 -90)
			(layer "B.Fab")
			(hide yes)
			(effects
				(font
					(size 0.7 0.7)
					(thickness 0.15)
				)
				(justify left bottom mirror)
			)
		)
		(fp_text user "License: Apache-2.0"
			(at -2.5 -7.884 -90)
			(layer "B.Fab")
			(hide yes)
			(effects
				(font
					(size 0.7 0.7)
					(thickness 0.15)
				)
				(justify left bottom mirror)
			)
		)
		(fp_text user "${REFERENCE}"
			(at -2.5 -5.884 -90)
			(layer "B.Fab")
			(hide yes)
			(effects
				(font
					(size 0.7 0.7)
					(thickness 0.15)
				)
				(justify left bottom mirror)
			)
		)
		(pad "1" smd roundrect
			(at -2.327 1.301 90)
			(size 0.75 0.31)
			(layers "B.Cu" "B.Paste" "B.Mask")
			(roundrect_rratio 0.25)
			(net 105 "/Ethernet/VDD")
			(pinfunction "VDD")
			(pintype "power_in")
		)
		(pad "2" smd roundrect
			(at -2.327 0.652 90)
			(size 0.75 0.31)
			(layers "B.Cu" "B.Paste" "B.Mask")
			(roundrect_rratio 0.25)
			(net 570 "/Ethernet/DEN")
			(pinfunction "DEN")
			(pintype "input")
		)
		(pad "3" smd roundrect
			(at -2.327 0 90)
			(size 0.75 0.31)
			(layers "B.Cu" "B.Paste" "B.Mask")
			(roundrect_rratio 0.25)
			(net 568 "/Ethernet/CLSA")
			(pinfunction "CLSA")
			(pintype "input")
		)
		(pad "4" smd roundrect
			(at -2.327 -0.65 90)
			(size 0.75 0.31)
			(layers "B.Cu" "B.Paste" "B.Mask")
			(roundrect_rratio 0.25)
			(net 499 "/Ethernet/VSS")
			(pinfunction "VSSA")
			(pintype "power_in")
		)
		(pad "5" smd roundrect
			(at -2.327 -1.3 90)
			(size 0.75 0.31)
			(layers "B.Cu" "B.Paste" "B.Mask")
			(roundrect_rratio 0.25)
			(net 499 "/Ethernet/VSS")
			(pinfunction "VSSB")
			(pintype "power_in")
		)
		(pad "6" smd roundrect
			(at -1.301 -2.325 90)
			(size 0.31 0.75)
			(layers "B.Cu" "B.Paste" "B.Mask")
			(roundrect_rratio 0.25)
			(net 569 "/Ethernet/CLSB")
			(pinfunction "CLSB")
			(pintype "input")
		)
		(pad "7" smd roundrect
			(at -0.652 -2.325 90)
			(size 0.31 0.75)
			(layers "B.Cu" "B.Paste" "B.Mask")
			(roundrect_rratio 0.25)
			(net 566 "/Ethernet/REF")
			(pinfunction "REF")
			(pintype "input")
		)
		(pad "8" smd roundrect
			(at 0 -2.325 90)
			(size 0.31 0.75)
			(layers "B.Cu" "B.Paste" "B.Mask")
			(roundrect_rratio 0.25)
			(net 565 "/Ethernet/AMPS_CTL")
			(pinfunction "AMPS_CTL")
			(pintype "input")
		)
		(pad "9" smd roundrect
			(at 0.65 -2.325 90)
			(size 0.31 0.75)
			(layers "B.Cu" "B.Paste" "B.Mask")
			(roundrect_rratio 0.25)
			(net 567 "/Ethernet/MPS_DUTY")
			(pinfunction "MPS_DUTY")
			(pintype "input")
		)
		(pad "10" smd roundrect
			(at 1.3 -2.325 90)
			(size 0.31 0.75)
			(layers "B.Cu" "B.Paste" "B.Mask")
			(roundrect_rratio 0.25)
			(net 704 "unconnected-(U22-~{AUTCLS}-Pad10)")
			(pinfunction "~{AUTCLS}")
			(pintype "input+no_connect")
		)
		(pad "11" smd roundrect
			(at 2.325 -1.3 90)
			(size 0.75 0.31)
			(layers "B.Cu" "B.Paste" "B.Mask")
			(roundrect_rratio 0.25)
			(net 106 "GNDD")
			(pinfunction "RTNA")
			(pintype "power_out")
		)
		(pad "12" smd roundrect
			(at 2.325 -0.65 90)
			(size 0.75 0.31)
			(layers "B.Cu" "B.Paste" "B.Mask")
			(roundrect_rratio 0.25)
			(net 106 "GNDD")
			(pinfunction "RTNB")
			(pintype "power_out")
		)
		(pad "13" smd roundrect
			(at 2.325 0 90)
			(size 0.75 0.31)
			(layers "B.Cu" "B.Paste" "B.Mask")
			(roundrect_rratio 0.25)
			(net 571 "/Ethernet/PG")
			(pinfunction "PG")
			(pintype "output")
		)
		(pad "14" smd roundrect
			(at 2.325 0.652 90)
			(size 0.75 0.31)
			(layers "B.Cu" "B.Paste" "B.Mask")
			(roundrect_rratio 0.25)
			(net 705 "unconnected-(U22-NC-Pad14)")
			(pinfunction "NC")
			(pintype "no_connect")
		)
		(pad "15" smd roundrect
			(at 2.325 1.301 90)
			(size 0.75 0.31)
			(layers "B.Cu" "B.Paste" "B.Mask")
			(roundrect_rratio 0.25)
			(net 706 "unconnected-(U22-NC-Pad15)")
			(pinfunction "NC")
			(pintype "no_connect")
		)
		(pad "16" smd roundrect
			(at 1.3 2.327 90)
			(size 0.31 0.75)
			(layers "B.Cu" "B.Paste" "B.Mask")
			(roundrect_rratio 0.25)
			(net 707 "unconnected-(U22-IRSHDL_EN-Pad16)")
			(pinfunction "IRSHDL_EN")
			(pintype "output+no_connect")
		)
		(pad "17" smd roundrect
			(at 0.65 2.327 90)
			(size 0.31 0.75)
			(layers "B.Cu" "B.Paste" "B.Mask")
			(roundrect_rratio 0.25)
			(net 573 "/Ethernet/TPL")
			(pinfunction "TPL")
			(pintype "output")
		)
		(pad "18" smd roundrect
			(at 0 2.327 90)
			(size 0.31 0.75)
			(layers "B.Cu" "B.Paste" "B.Mask")
			(roundrect_rratio 0.25)
			(net 572 "/Ethernet/TPH")
			(pinfunction "TPH")
			(pintype "output")
		)
		(pad "19" smd roundrect
			(at -0.652 2.327 90)
			(size 0.31 0.75)
			(layers "B.Cu" "B.Paste" "B.Mask")
			(roundrect_rratio 0.25)
			(net 574 "/Ethernet/~{BT}")
			(pinfunction "~{BT}")
			(pintype "output")
		)
		(pad "20" smd roundrect
			(at -1.301 2.327 90)
			(size 0.31 0.75)
			(layers "B.Cu" "B.Paste" "B.Mask")
			(roundrect_rratio 0.25)
			(net 709 "unconnected-(U22-NC-Pad20)")
			(pinfunction "NC")
			(pintype "no_connect")
		)
		(pad "21" smd rect
			(at 0 0 90)
			(size 2.2 2.2)
			(layers "B.Cu" "B.Mask")
			(net 499 "/Ethernet/VSS")
			(pinfunction "PAD_VSSC")
			(pintype "power_in")
		)
	)
	(footprint "antmicro-footprints:LED_0603_1608Metric_G"
		(layer "B.Cu")
		(at 60.55 127.2 90)
		(descr "LED SMD 0603 Green")
		(tags "LED SMD 0603 Green")
		(property "Reference" "D8"
			(at -0.7 1.65 90)
			(layer "B.SilkS")
			(effects
				(font
					(size 0.7 0.7)
					(thickness 0.15)
				)
				(justify right bottom mirror)
			)
		)
		(property "Value" "LED_G_0603_LTST-C190GKT"
			(at -0.001 -1.599 90)
			(layer "B.Fab")
			(effects
				(font
					(size 0.7 0.7)
					(thickness 0.15)
				)
				(justify right bottom mirror)
			)
		)
		(property "Footprint" "antmicro-footprints:LED_0603_1608Metric_G"
			(at 0 0 90)
			(layer "F.Fab")
			(hide yes)
			(effects
				(font
					(size 1.27 1.27)
					(thickness 0.15)
				)
			)
		)
		(property "Datasheet" "https://media.digikey.com/pdf/Data%20Sheets/Lite-On%20PDFs/LTST-C190GKT.pdf"
			(at 0 0 90)
			(layer "F.Fab")
			(hide yes)
			(effects
				(font
					(size 1.27 1.27)
					(thickness 0.15)
				)
			)
		)
		(property "Author" "Antmicro"
			(at 187.75 66.65 0)
			(layer "B.Fab")
			(hide yes)
			(effects
				(font
					(size 1 1)
					(thickness 0.15)
				)
				(justify mirror)
			)
		)
		(property "Color" "Green"
			(at 187.75 66.65 0)
			(layer "B.Fab")
			(hide yes)
			(effects
				(font
					(size 1 1)
					(thickness 0.15)
				)
				(justify mirror)
			)
		)
		(property "License" "Apache-2.0"
			(at 187.75 66.65 0)
			(layer "B.Fab")
			(hide yes)
			(effects
				(font
					(size 1 1)
					(thickness 0.15)
				)
				(justify mirror)
			)
		)
		(property "MPN" "LTST-C190GKT"
			(at 187.75 66.65 0)
			(layer "B.Fab")
			(hide yes)
			(effects
				(font
					(size 1 1)
					(thickness 0.15)
				)
				(justify mirror)
			)
		)
		(property "Manufacturer" "Lite-On"
			(at 187.75 66.65 0)
			(layer "B.Fab")
			(hide yes)
			(effects
				(font
					(size 1 1)
					(thickness 0.15)
				)
				(justify mirror)
			)
		)
		(sheetname "USB Debug, DP")
		(sheetfile "usb.kicad_sch")
		(attr smd)
		(fp_line
			(start -0.22 -0.35)
			(end 0.22 -0.35)
			(stroke
				(width 0.15)
				(type solid)
			)
			(layer "B.SilkS")
		)
		(fp_line
			(start -1.18 -0.321)
			(end -1.18 0.319)
			(stroke
				(width 0.15)
				(type solid)
			)
			(layer "B.SilkS")
		)
		(fp_line
			(start -0.094672 -0.001008)
			(end 0.105328 -0.201008)
			(stroke
				(width 0.1)
				(type solid)
			)
			(layer "B.SilkS")
		)
		(fp_line
			(start -0.24 -0.001008)
			(end -0.094672 -0.001008)
			(stroke
				(width 0.1)
				(type solid)
			)
			(layer "B.SilkS")
		)
		(fp_line
			(start 0.24 -0.001)
			(end 0.105328 -0.001008)
			(stroke
				(width 0.1)
				(type solid)
			)
			(layer "B.SilkS")
		)
		(fp_line
			(start 0.105328 0.198992)
			(end 0.105328 -0.201008)
			(stroke
				(width 0.1)
				(type solid)
			)
			(layer "B.SilkS")
		)
		(fp_line
			(start 0.105328 0.198992)
			(end -0.094672 -0.001008)
			(stroke
				(width 0.1)
				(type solid)
			)
			(layer "B.SilkS")
		)
		(fp_line
			(start -0.094672 0.198992)
			(end -0.094672 -0.201008)
			(stroke
				(width 0.1)
				(type solid)
			)
			(layer "B.SilkS")
		)
		(fp_line
			(start -0.22 0.35)
			(end 0.22 0.35)
			(stroke
				(width 0.15)
				(type solid)
			)
			(layer "B.SilkS")
		)
		(fp_rect
			(start 1.25 -0.65)
			(end -1.25 0.65)
			(stroke
				(width 0.05)
				(type solid)
			)
			(fill none)
			(layer "B.CrtYd")
		)
		(fp_line
			(start 0.201 -0.2)
			(end -0.101 0)
			(stroke
				(width 0.15)
				(type solid)
			)
			(layer "B.Fab")
		)
		(fp_line
			(start -0.199 -0.1)
			(end -0.199 -0.2)
			(stroke
				(width 0.15)
				(type solid)
			)
			(layer "B.Fab")
		)
		(fp_line
			(start -0.199 -0.1)
			(end -0.199 0.202)
			(stroke
				(width 0.15)
				(type solid)
			)
			(layer "B.Fab")
		)
		(fp_line
			(start 0.201 0)
			(end 0.201 -0.2)
			(stroke
				(width 0.15)
				(type solid)
			)
			(layer "B.Fab")
		)
		(fp_line
			(start 0.201 0)
			(end 0.599 0)
			(stroke
				(width 0.15)
				(type solid)
			)
			(layer "B.Fab")
		)
		(fp_line
			(start -0.101 0)
			(end 0.201 0.202)
			(stroke
				(width 0.15)
				(type solid)
			)
			(layer "B.Fab")
		)
		(fp_line
			(start -0.597 0)
			(end -0.199 0)
			(stroke
				(width 0.15)
				(type solid)
			)
			(layer "B.Fab")
		)
		(fp_line
			(start 0.201 0.202)
			(end 0.201 0)
			(stroke
				(width 0.15)
				(type solid)
			)
			(layer "B.Fab")
		)
		(fp_rect
			(start 0.848 -0.4)
			(end -0.85 0.402)
			(stroke
				(width 0.15)
				(type solid)
			)
			(fill none)
			(layer "B.Fab")
		)
		(fp_text user "License: Apache-2.0"
			(at -1.4224 -3.599 90)
			(layer "B.Fab")
			(hide yes)
			(effects
				(font
					(size 0.7 0.7)
					(thickness 0.15)
				)
				(justify right bottom mirror)
			)
		)
		(fp_text user "${REFERENCE}"
			(at -1.4224 -5.999 90)
			(layer "B.Fab")
			(hide yes)
			(effects
				(font
					(size 0.7 0.7)
					(thickness 0.15)
				)
				(justify right bottom mirror)
			)
		)
		(fp_text user "Author: Antmicro"
			(at -1.4224 -4.799 90)
			(layer "B.Fab")
			(hide yes)
			(effects
				(font
					(size 0.7 0.7)
					(thickness 0.15)
				)
				(justify right bottom mirror)
			)
		)
		(pad "1" smd roundrect
			(at -0.7 0 270)
			(size 0.8 1)
			(layers "B.Cu" "B.Paste" "B.Mask")
			(roundrect_rratio 0.2)
			(net 1 "GND")
			(pinfunction "C")
			(pintype "passive")
		)
		(pad "2" smd roundrect
			(at 0.7 0 270)
			(size 0.8 1)
			(layers "B.Cu" "B.Paste" "B.Mask")
			(roundrect_rratio 0.2)
			(net 146 "Net-(D8-A)")
			(pinfunction "A")
			(pintype "passive")
		)
	)
	(footprint "antmicro-footprints:R_0402_1005Metric"
		(layer "B.Cu")
		(at 57.55 112.45 180)
		(descr "Resistor SMD 0402")
		(tags "resistor SMD 0402")
		(property "Reference" "R57"
			(at -3.02 -0.34 0)
			(layer "B.SilkS")
			(effects
				(font
					(size 0.7 0.7)
					(thickness 0.15)
				)
				(justify left bottom mirror)
			)
		)
		(property "Value" "R_0R_0402"
			(at 0 -1.4 0)
			(layer "B.Fab")
			(effects
				(font
					(size 0.7 0.7)
					(thickness 0.15)
				)
				(justify left bottom mirror)
			)
		)
		(property "Footprint" "antmicro-footprints:R_0402_1005Metric"
			(at 0 0 180)
			(layer "F.Fab")
			(hide yes)
			(effects
				(font
					(size 1.27 1.27)
					(thickness 0.15)
				)
			)
		)
		(property "Datasheet" "https://industrial.panasonic.com/cdbs/www-data/pdf/RDA0000/AOA0000C301.pdf"
			(at 0 0 180)
			(layer "F.Fab")
			(hide yes)
			(effects
				(font
					(size 1.27 1.27)
					(thickness 0.15)
				)
			)
		)
		(property "Author" "Antmicro"
			(at 115.1 224.9 0)
			(layer "B.Fab")
			(hide yes)
			(effects
				(font
					(size 1 1)
					(thickness 0.15)
				)
				(justify mirror)
			)
		)
		(property "Current" "1A"
			(at 115.1 224.9 0)
			(layer "B.Fab")
			(hide yes)
			(effects
				(font
					(size 1 1)
					(thickness 0.15)
				)
				(justify mirror)
			)
		)
		(property "License" "Apache-2.0"
			(at 115.1 224.9 0)
			(layer "B.Fab")
			(hide yes)
			(effects
				(font
					(size 1 1)
					(thickness 0.15)
				)
				(justify mirror)
			)
		)
		(property "MPN" "ERJ2GE0R00X"
			(at 115.1 224.9 0)
			(layer "B.Fab")
			(hide yes)
			(effects
				(font
					(size 1 1)
					(thickness 0.15)
				)
				(justify mirror)
			)
		)
		(property "Manufacturer" "Panasonic"
			(at 115.1 224.9 0)
			(layer "B.Fab")
			(hide yes)
			(effects
				(font
					(size 1 1)
					(thickness 0.15)
				)
				(justify mirror)
			)
		)
		(property "Tolerance" ""
			(at 115.1 224.9 0)
			(layer "B.Fab")
			(hide yes)
			(effects
				(font
					(size 1 1)
					(thickness 0.15)
				)
				(justify mirror)
			)
		)
		(property "Val" "0R"
			(at 115.1 224.9 0)
			(layer "B.Fab")
			(hide yes)
			(effects
				(font
					(size 1 1)
					(thickness 0.15)
				)
				(justify mirror)
			)
		)
		(sheetname "USB Debug, DP")
		(sheetfile "usb.kicad_sch")
		(attr smd)
		(fp_rect
			(start -0.925 0.47)
			(end 0.925 -0.47)
			(stroke
				(width 0.05)
				(type default)
			)
			(fill none)
			(layer "B.CrtYd")
		)
		(fp_rect
			(start -0.5 0.25)
			(end 0.5 -0.25)
			(stroke
				(width 0.15)
				(type solid)
			)
			(fill none)
			(layer "B.Fab")
		)
		(fp_text user "${REFERENCE}"
			(at -0.95 -3.168 0)
			(layer "B.Fab")
			(hide yes)
			(effects
				(font
					(size 0.7 0.7)
					(thickness 0.15)
				)
				(justify left bottom mirror)
			)
		)
		(fp_text user "License: Apache-2.0"
			(at -0.95 -5.169 0)
			(layer "B.Fab")
			(hide yes)
			(effects
				(font
					(size 0.7 0.7)
					(thickness 0.15)
				)
				(justify left bottom mirror)
			)
		)
		(fp_text user "Author: Antmicro"
			(at -0.95 -4.169 0)
			(layer "B.Fab")
			(hide yes)
			(effects
				(font
					(size 0.7 0.7)
					(thickness 0.15)
				)
				(justify left bottom mirror)
			)
		)
		(pad "1" smd roundrect
			(at -0.48 0 180)
			(size 0.59 0.64)
			(layers "B.Cu" "B.Paste" "B.Mask")
			(roundrect_rratio 0.25)
			(net 475 "DEBUG_TXD")
			(pintype "passive")
		)
		(pad "2" smd roundrect
			(at 0.48 0 180)
			(size 0.59 0.64)
			(layers "B.Cu" "B.Paste" "B.Mask")
			(roundrect_rratio 0.25)
			(net 647 "Net-(U5-RXD)")
			(pintype "passive")
		)
	)
)
